# T6G (Grand Teton) — schematic netlist excerpt (pin names and nets, part order shuffled) for the footprints in the layout excerpt that follows; sources: Cadence DE-HDL packaged netlist, KiCad conversion of 04192023_DAF0TMB3IC0_F0TG_MB_C_brd_V02_OCP.brd

C2480  Q_CAP  22UF 4V 20% X6S  pkg C0402  page 74 : A = PVDD11_S3_P1 ; B = GND
R436  Q_RES  0 5% CHIP  pkg 0402LF  page 28 : A = CLK_100M_REF_OUT_DN ; B = CLK_100M_REF_IN_DN

(kicad_pcb
	(version 20260206)
	(generator "pcbnew")
	(generator_version "10.0")
	(general
		(thickness 1.6)
		(legacy_teardrops no)
	)
	(paper "A4")
	(title_block
		(title "04192023_DAF0TMB3IC0_F0TG_MB_C_brd_V02_OCP.brd")
		(comment 1 "Grand Teton / footprints 7654-7655 of 8354")
	)
	(layers
		(0 "F.Cu" signal "TOP")
		(4 "In1.Cu" signal "GND")
		(6 "In2.Cu" signal "IN1")
		(8 "In3.Cu" signal "GND1")
		(10 "In4.Cu" signal "IN2")
		(12 "In5.Cu" signal "GND2")
		(14 "In6.Cu" signal "IN3")
		(16 "In7.Cu" signal "GND3")
		(18 "In8.Cu" signal "VCC")
		(20 "In9.Cu" signal "VCC1")
		(22 "In10.Cu" signal "GND4")
		(24 "In11.Cu" signal "IN4")
		(26 "In12.Cu" signal "GND5")
		(28 "In13.Cu" signal "IN5")
		(30 "In14.Cu" signal "GND6")
		(32 "In15.Cu" signal "IN6")
		(34 "In16.Cu" signal "GND7")
		(2 "B.Cu" signal "BOTTOM")
		(9 "F.Adhes" user "F.Adhesive")
		(11 "B.Adhes" user "B.Adhesive")
		(13 "F.Paste" user "Package Geometry/Pastemask Top")
		(15 "B.Paste" user "Package Geometry/Pastemask Bottom")
		(5 "F.SilkS" user "Ref Des/Silkscreen Top")
		(7 "B.SilkS" user "Ref Des/Silkscreen Bottom")
		(1 "F.Mask" user "Board Geometry/Soldermask Top")
		(3 "B.Mask" user "Board Geometry/Soldermask Bottom")
		(17 "Dwgs.User" user "User.Drawings")
		(19 "Cmts.User" user "User.Comments")
		(21 "Eco1.User" user "User.Eco1")
		(23 "Eco2.User" user "User.Eco2")
		(25 "Edge.Cuts" user "Board Geometry/Outline")
		(27 "Margin" user)
		(31 "F.CrtYd" user "Package Geometry/Place Bound Top")
		(29 "B.CrtYd" user "Package Geometry/Place Bound Bottom")
		(35 "F.Fab" user "Ref Des/Assembly Top")
		(33 "B.Fab" user "Ref Des/Assembly Bottom")
	)
	(footprint ""
		(layer "B.Cu")
		(at 121.579386 -266.005564)
		(property "Reference" "C2480"
			(at 0 0 0)
			(layer "B.SilkS")
			(hide yes)
			(effects
				(font
					(size 1.27 1.27)
				)
				(justify mirror)
			)
		)
		(property "Value" ""
			(at 0 0 0)
			(layer "B.Fab")
			(effects
				(font
					(size 1.27 1.27)
				)
				(justify mirror)
			)
		)
		(duplicate_pad_numbers_are_jumpers no)
		(fp_line
			(start -0.7874 -0.4064)
			(end -0.7874 0.4064)
			(stroke
				(width 0.1524)
				(type default)
			)
			(layer "B.SilkS")
		)
		(fp_line
			(start -0.7874 0.4064)
			(end 0.7874 0.4064)
			(stroke
				(width 0.1524)
				(type default)
			)
			(layer "B.SilkS")
		)
		(fp_line
			(start 0.7874 -0.4064)
			(end -0.7874 -0.4064)
			(stroke
				(width 0.1524)
				(type default)
			)
			(layer "B.SilkS")
		)
		(fp_line
			(start 0.7874 0.4064)
			(end 0.7874 -0.4064)
			(stroke
				(width 0.1524)
				(type default)
			)
			(layer "B.SilkS")
		)
		(fp_line
			(start -0.67945 -0.3048)
			(end -0.67945 0.3048)
			(stroke
				(width 0.1)
				(type default)
			)
			(layer "B.Fab")
		)
		(fp_line
			(start -0.67945 0.3048)
			(end -0.120396 0.3048)
			(stroke
				(width 0.1)
				(type default)
			)
			(layer "B.Fab")
		)
		(fp_line
			(start -0.12065 -0.3048)
			(end -0.67945 -0.3048)
			(stroke
				(width 0.1)
				(type default)
			)
			(layer "B.Fab")
		)
		(fp_line
			(start -0.12065 -0.2794)
			(end -0.12065 -0.3048)
			(stroke
				(width 0.1)
				(type default)
			)
			(layer "B.Fab")
		)
		(fp_line
			(start -0.120396 0.2794)
			(end 0.12065 0.2794)
			(stroke
				(width 0.1)
				(type default)
			)
			(layer "B.Fab")
		)
		(fp_line
			(start -0.120396 0.3048)
			(end -0.120396 0.2794)
			(stroke
				(width 0.1)
				(type default)
			)
			(layer "B.Fab")
		)
		(fp_line
			(start 0.12065 -0.305054)
			(end 0.12065 -0.2794)
			(stroke
				(width 0.1)
				(type default)
			)
			(layer "B.Fab")
		)
		(fp_line
			(start 0.12065 -0.2794)
			(end -0.12065 -0.2794)
			(stroke
				(width 0.1)
				(type default)
			)
			(layer "B.Fab")
		)
		(fp_line
			(start 0.12065 0.2794)
			(end 0.12065 0.3048)
			(stroke
				(width 0.1)
				(type default)
			)
			(layer "B.Fab")
		)
		(fp_line
			(start 0.12065 0.3048)
			(end 0.67945 0.3048)
			(stroke
				(width 0.1)
				(type default)
			)
			(layer "B.Fab")
		)
		(fp_line
			(start 0.67945 -0.305054)
			(end 0.12065 -0.305054)
			(stroke
				(width 0.1)
				(type default)
			)
			(layer "B.Fab")
		)
		(fp_line
			(start 0.67945 0.3048)
			(end 0.67945 -0.305054)
			(stroke
				(width 0.1)
				(type default)
			)
			(layer "B.Fab")
		)
		(pad "1" smd circle
			(at 0.40005 0 180)
			(size 0 0)
			(layers "B.Cu" "B.Mask" "B.Paste")
			(net "PVDD11_S3_P1")
		)
		(pad "2" smd circle
			(at -0.40005 0 180)
			(size 0 0)
			(layers "B.Cu" "B.Mask" "B.Paste")
			(net "GND")
		)
	)
	(footprint ""
		(layer "B.Cu")
		(at 338.550758 -214.880952 90)
		(property "Reference" "R436"
			(at 0 0 90)
			(layer "B.SilkS")
			(hide yes)
			(effects
				(font
					(size 1.27 1.27)
				)
				(justify mirror)
			)
		)
		(property "Value" ""
			(at 0 0 90)
			(layer "B.Fab")
			(effects
				(font
					(size 1.27 1.27)
				)
				(justify mirror)
			)
		)
		(duplicate_pad_numbers_are_jumpers no)
		(fp_line
			(start 0.7874 -0.4064)
			(end -0.7874 -0.4064)
			(stroke
				(width 0.1524)
				(type default)
			)
			(layer "B.SilkS")
		)
		(fp_line
			(start -0.7874 -0.4064)
			(end -0.7874 -0.095758)
			(stroke
				(width 0.1524)
				(type default)
			)
			(layer "B.SilkS")
		)
		(fp_line
			(start 0.7874 -0.019558)
			(end 0.7874 -0.4064)
			(stroke
				(width 0.1524)
				(type default)
			)
			(layer "B.SilkS")
		)
		(fp_line
			(start -0.377952 0.4064)
			(end 0.384048 0.4064)
			(stroke
				(width 0.1524)
				(type default)
			)
			(layer "B.SilkS")
		)
		(fp_line
			(start 0.67945 -0.305054)
			(end 0.12065 -0.305054)
			(stroke
				(width 0.1)
				(type default)
			)
			(layer "B.Fab")
		)
		(fp_line
			(start 0.12065 -0.305054)
			(end 0.12065 -0.2794)
			(stroke
				(width 0.1)
				(type default)
			)
			(layer "B.Fab")
		)
		(fp_line
			(start -0.12065 -0.3048)
			(end -0.67945 -0.3048)
			(stroke
				(width 0.1)
				(type default)
			)
			(layer "B.Fab")
		)
		(fp_line
			(start -0.67945 -0.3048)
			(end -0.67945 0.3048)
			(stroke
				(width 0.1)
				(type default)
			)
			(layer "B.Fab")
		)
		(fp_line
			(start 0.12065 -0.2794)
			(end -0.12065 -0.2794)
			(stroke
				(width 0.1)
				(type default)
			)
			(layer "B.Fab")
		)
		(fp_line
			(start -0.12065 -0.2794)
			(end -0.12065 -0.3048)
			(stroke
				(width 0.1)
				(type default)
			)
			(layer "B.Fab")
		)
		(fp_line
			(start 0.12065 0.2794)
			(end 0.12065 0.3048)
			(stroke
				(width 0.1)
				(type default)
			)
			(layer "B.Fab")
		)
		(fp_line
			(start -0.120396 0.2794)
			(end 0.12065 0.2794)
			(stroke
				(width 0.1)
				(type default)
			)
			(layer "B.Fab")
		)
		(fp_line
			(start 0.67945 0.3048)
			(end 0.67945 -0.305054)
			(stroke
				(width 0.1)
				(type default)
			)
			(layer "B.Fab")
		)
		(fp_line
			(start 0.12065 0.3048)
			(end 0.67945 0.3048)
			(stroke
				(width 0.1)
				(type default)
			)
			(layer "B.Fab")
		)
		(fp_line
			(start -0.120396 0.3048)
			(end -0.120396 0.2794)
			(stroke
				(width 0.1)
				(type default)
			)
			(layer "B.Fab")
		)
		(fp_line
			(start -0.67945 0.3048)
			(end -0.120396 0.3048)
			(stroke
				(width 0.1)
				(type default)
			)
			(layer "B.Fab")
		)
		(pad "1" smd circle
			(at 0.40005 0 270)
			(size 0 0)
			(layers "B.Cu" "B.Mask" "B.Paste")
			(net "CLK_100M_REF_OUT_DN")
		)
		(pad "2" smd circle
			(at -0.40005 0 270)
			(size 0 0)
			(layers "B.Cu" "B.Mask" "B.Paste")
			(net "CLK_100M_REF_IN_DN")
		)
	)
)
